# BASEBOARD_FAB2 (Tioga Pass) — schematic netlist excerpt (pin names and nets, part order shuffled) for the footprints in the layout excerpt that follows; sources: Cadence DE-HDL packaged netlist, KiCad conversion of Wiwynn_Tioga_Pass_MB.brd

R8G2  RES  4.75K 1% CHIP  pkg 0402  page 156 : A = P3V3_STBY ; B = FM_PCH_PWRBTN_OUT_N
FB2T2  FERRITE  600 FB  pkg SMLF  page 101 : A = P3V3_STBY ; B = P3V3_STBY_MNG
C3N2  CAP_A  1.0UF 6.3V 10% X6S  pkg 0402V  page 132 : A = PVNN_PCH_STBY ; B = GND

(kicad_pcb
	(version 20260206)
	(generator "pcbnew")
	(generator_version "10.0")
	(general
		(thickness 1.6)
		(legacy_teardrops no)
	)
	(paper "A4")
	(title_block
		(title "Wiwynn_Tioga_Pass_MB.brd")
		(comment 1 "Tioga Pass / footprints 3360-3362 of 4770")
	)
	(layers
		(0 "F.Cu" signal "TOP")
		(4 "In1.Cu" signal "L2GND")
		(6 "In2.Cu" signal "L3")
		(8 "In3.Cu" signal "L4GND")
		(10 "In4.Cu" signal "L5")
		(12 "In5.Cu" signal "L6GND")
		(14 "In6.Cu" signal "L7VCC")
		(16 "In7.Cu" signal "L8VCC")
		(18 "In8.Cu" signal "L9GND")
		(20 "In9.Cu" signal "L10")
		(22 "In10.Cu" signal "L11GND")
		(24 "In11.Cu" signal "L12")
		(26 "In12.Cu" signal "L13GND")
		(2 "B.Cu" signal "BOTTOM")
		(9 "F.Adhes" user "F.Adhesive")
		(11 "B.Adhes" user "B.Adhesive")
		(13 "F.Paste" user "Package Geometry/Pastemask Top")
		(15 "B.Paste" user "Package Geometry/Pastemask Bottom")
		(5 "F.SilkS" user "Ref Des/Silkscreen Top")
		(7 "B.SilkS" user "Ref Des/Silkscreen Bottom")
		(1 "F.Mask" user "Board Geometry/Soldermask Top")
		(3 "B.Mask" user "Board Geometry/Soldermask Bottom")
		(17 "Dwgs.User" user "User.Drawings")
		(19 "Cmts.User" user "User.Comments")
		(21 "Eco1.User" user "User.Eco1")
		(23 "Eco2.User" user "User.Eco2")
		(25 "Edge.Cuts" user "Board Geometry/Outline")
		(27 "Margin" user)
		(31 "F.CrtYd" user "Package Geometry/Place Bound Top")
		(29 "B.CrtYd" user "Package Geometry/Place Bound Bottom")
		(35 "F.Fab" user "Ref Des/Assembly Top")
		(33 "B.Fab" user "Ref Des/Assembly Bottom")
	)
	(footprint ""
		(layer "B.Cu")
		(at 485.267 -30.226)
		(property "Reference" "FB2T2"
			(at -1.34747 0.197104 270)
			(unlocked yes)
			(layer "B.SilkS")
			(effects
				(font
					(size 0.7874 0.5842)
					(thickness 0.1524)
				)
				(justify mirror)
			)
		)
		(property "Value" ""
			(at 0 0 0)
			(layer "B.Fab")
			(effects
				(font
					(size 1.27 1.27)
				)
				(justify mirror)
			)
		)
		(duplicate_pad_numbers_are_jumpers no)
		(fp_poly
			(pts
				(xy 0.7239 -0.26035) (xy -0.7239 -0.26035) (xy -0.7239 2.03835) (xy 0.7239 2.03835)
			)
			(stroke
				(width 0)
				(type default)
			)
			(fill no)
			(layer "B.CrtYd")
		)
		(fp_line
			(start -0.7239 -0.26035)
			(end -0.7239 2.03835)
			(stroke
				(width 0.1)
				(type default)
			)
			(layer "B.Fab")
		)
		(fp_line
			(start -0.7239 2.03835)
			(end 0.7239 2.03835)
			(stroke
				(width 0.1)
				(type default)
			)
			(layer "B.Fab")
		)
		(fp_line
			(start 0.7239 -0.26035)
			(end -0.7239 -0.26035)
			(stroke
				(width 0.1)
				(type default)
			)
			(layer "B.Fab")
		)
		(fp_line
			(start 0.7239 2.03835)
			(end 0.7239 -0.26035)
			(stroke
				(width 0.1)
				(type default)
			)
			(layer "B.Fab")
		)
		(pad "1" smd rect
			(at 0 0 180)
			(size 1.27 1.016)
			(layers "B.Cu" "B.Mask" "B.Paste")
			(net "P3V3_STBY")
		)
		(pad "2" smd rect
			(at 0 1.778 180)
			(size 1.27 1.016)
			(layers "B.Cu" "B.Mask" "B.Paste")
			(net "P3V3_STBY_MNG")
		)
		(zone
			(layer "B.Cu")
			(hatch none 0.5)
			(connect_pads
				(clearance 0)
			)
			(min_thickness 0.25)
			(keepout
				(tracks not_allowed)
				(vias allowed)
				(pads allowed)
				(copperpour not_allowed)
				(footprints allowed)
			)
			(placement
				(enabled no)
				(sheetname "")
			)
			(fill
				(thermal_gap 0.5)
				(thermal_bridge_width 0.5)
				(island_removal_mode 0)
			)
			(polygon
				(pts
					(xy 484.632 -29.718) (xy 484.632 -28.956) (xy 484.7209 -28.956) (xy 485.902 -28.956) (xy 485.902 -29.718)
				)
			)
		)
	)
	(footprint ""
		(layer "B.Cu")
		(at 384.53695 -111.85525 180)
		(property "Reference" "C3N2"
			(at 0 0 0)
			(layer "B.SilkS")
			(hide yes)
			(effects
				(font
					(size 1.27 1.27)
				)
				(justify mirror)
			)
		)
		(property "Value" ""
			(at 0 0 0)
			(layer "B.Fab")
			(effects
				(font
					(size 1.27 1.27)
				)
				(justify mirror)
			)
		)
		(duplicate_pad_numbers_are_jumpers no)
		(fp_rect
			(start 0.2794 0.9144)
			(end -0.2794 -0.1143)
			(stroke
				(width 0)
				(type default)
			)
			(fill no)
			(layer "B.CrtYd")
		)
		(fp_line
			(start 0.2794 0.9144)
			(end 0.2794 -0.1143)
			(stroke
				(width 0.1)
				(type default)
			)
			(layer "B.Fab")
		)
		(fp_line
			(start 0.2794 -0.1143)
			(end -0.2794 -0.1143)
			(stroke
				(width 0.1)
				(type default)
			)
			(layer "B.Fab")
		)
		(fp_line
			(start -0.2794 0.9144)
			(end 0.2794 0.9144)
			(stroke
				(width 0.1)
				(type default)
			)
			(layer "B.Fab")
		)
		(fp_line
			(start -0.2794 -0.1143)
			(end -0.2794 0.9144)
			(stroke
				(width 0.1)
				(type default)
			)
			(layer "B.Fab")
		)
		(pad "1" smd custom
			(at 0 0 90)
			(size 0.10414 0.10414)
			(layers "B.Cu" "B.Mask" "B.Paste")
			(net "PVNN_PCH_STBY")
			(options
				(clearance outline)
				(anchor circle)
			)
			(primitives
				(gr_poly
					(pts
						(xy -0.20828 -0.08636) (xy -0.20828 0.08636) (xy -0.08636 0.20828) (xy 0.086614 0.20828) (xy 0.20828 0.086614)
						(xy 0.20828 -0.08636) (xy 0.08636 -0.20828) (xy -0.08636 -0.20828)
					)
					(width 0)
					(fill yes)
				)
			)
		)
		(pad "2" smd custom
			(at 0 0.8001 90)
			(size 0.10414 0.10414)
			(layers "B.Cu" "B.Mask" "B.Paste")
			(net "GND")
			(options
				(clearance outline)
				(anchor circle)
			)
			(primitives
				(gr_poly
					(pts
						(xy -0.20828 -0.08636) (xy -0.20828 0.08636) (xy -0.08636 0.20828) (xy 0.086614 0.20828) (xy 0.20828 0.086614)
						(xy 0.20828 -0.08636) (xy 0.08636 -0.20828) (xy -0.08636 -0.20828)
					)
					(width 0)
					(fill yes)
				)
			)
		)
		(zone
			(layer "B.Cu")
			(hatch none 0.5)
			(connect_pads
				(clearance 0)
			)
			(min_thickness 0.25)
			(keepout
				(tracks not_allowed)
				(vias allowed)
				(pads allowed)
				(copperpour not_allowed)
				(footprints allowed)
			)
			(placement
				(enabled no)
				(sheetname "")
			)
			(fill
				(thermal_gap 0.5)
				(thermal_bridge_width 0.5)
				(island_removal_mode 0)
			)
			(polygon
				(pts
					(xy 384.44932 -112.0648) (xy 384.44932 -112.4458) (xy 384.62458 -112.4458) (xy 384.624834 -112.0648)
				)
			)
		)
		(zone
			(layer "B.Cu")
			(hatch none 0.5)
			(connect_pads
				(clearance 0)
			)
			(min_thickness 0.25)
			(keepout
				(tracks allowed)
				(vias not_allowed)
				(pads allowed)
				(copperpour not_allowed)
				(footprints allowed)
			)
			(placement
				(enabled no)
				(sheetname "")
			)
			(fill
				(thermal_gap 0.5)
				(thermal_bridge_width 0.5)
				(island_removal_mode 0)
			)
			(polygon
				(pts
					(xy 384.44932 -112.0648) (xy 384.44932 -112.4458) (xy 384.62458 -112.4458) (xy 384.624834 -112.0648)
				)
			)
		)
	)
	(footprint ""
		(layer "B.Cu")
		(at 397.637 -37.846 180)
		(property "Reference" "R8G2"
			(at 0 0 0)
			(layer "B.SilkS")
			(hide yes)
			(effects
				(font
					(size 1.27 1.27)
				)
				(justify mirror)
			)
		)
		(property "Value" ""
			(at 0 0 0)
			(layer "B.Fab")
			(effects
				(font
					(size 1.27 1.27)
				)
				(justify mirror)
			)
		)
		(duplicate_pad_numbers_are_jumpers no)
		(fp_poly
			(pts
				(xy 0.2794 -0.1016) (xy -0.2794 -0.1016) (xy -0.2794 0.9906) (xy 0.2794 0.9906)
			)
			(stroke
				(width 0)
				(type default)
			)
			(fill no)
			(layer "B.CrtYd")
		)
		(fp_line
			(start 0.2794 0.9906)
			(end -0.2794 0.9906)
			(stroke
				(width 0.1)
				(type default)
			)
			(layer "B.Fab")
		)
		(fp_line
			(start 0.2794 -0.1016)
			(end 0.2794 0.9906)
			(stroke
				(width 0.1)
				(type default)
			)
			(layer "B.Fab")
		)
		(fp_line
			(start -0.2794 0.9906)
			(end -0.2794 -0.1016)
			(stroke
				(width 0.1)
				(type default)
			)
			(layer "B.Fab")
		)
		(fp_line
			(start -0.2794 -0.1016)
			(end 0.2794 -0.1016)
			(stroke
				(width 0.1)
				(type default)
			)
			(layer "B.Fab")
		)
		(pad "1" smd rect
			(at 0 0)
			(size 0.508 0.508)
			(layers "B.Cu" "B.Mask" "B.Paste")
			(net "P3V3_STBY")
		)
		(pad "2" smd rect
			(at 0 0.889)
			(size 0.508 0.508)
			(layers "B.Cu" "B.Mask" "B.Paste")
			(net "FM_PCH_PWRBTN_OUT_N")
		)
		(zone
			(layer "B.Cu")
			(hatch none 0.5)
			(connect_pads
				(clearance 0)
			)
			(min_thickness 0.25)
			(keepout
				(tracks not_allowed)
				(vias allowed)
				(pads allowed)
				(copperpour not_allowed)
				(footprints allowed)
			)
			(placement
				(enabled no)
				(sheetname "")
			)
			(fill
				(thermal_gap 0.5)
				(thermal_bridge_width 0.5)
				(island_removal_mode 0)
			)
			(polygon
				(pts
					(xy 397.383 -38.481) (xy 397.891 -38.481) (xy 397.891 -38.1) (xy 397.383 -38.1)
				)
			)
		)
		(zone
			(layer "B.Cu")
			(hatch none 0.5)
			(connect_pads
				(clearance 0)
			)
			(min_thickness 0.25)
			(keepout
				(tracks allowed)
				(vias not_allowed)
				(pads allowed)
				(copperpour not_allowed)
				(footprints allowed)
			)
			(placement
				(enabled no)
				(sheetname "")
			)
			(fill
				(thermal_gap 0.5)
				(thermal_bridge_width 0.5)
				(island_removal_mode 0)
			)
			(polygon
				(pts
					(xy 397.383 -38.1) (xy 397.891 -38.1) (xy 397.891 -38.481) (xy 397.383 -38.481)
				)
			)
		)
	)
)
